(kicad_pcb
	(version 20260206)
	(generator "pcbnew")
	(generator_version "10.0")
	(general
		(thickness 1.6)
		(legacy_teardrops no)
	)
	(paper "A4")
	(title_block
		(title "12092022_DA0F0TFB6D0_F0T_FAN_BOARD_MP5048_D_brd_v02_OCP.brd")
		(comment 1 "Grand Teton / footprints 346-350 of 924")
	)
	(layers
		(0 "F.Cu" signal "TOP")
		(4 "In1.Cu" signal "GND")
		(6 "In2.Cu" signal "IN1")
		(8 "In3.Cu" signal "IN2")
		(10 "In4.Cu" signal "GND1")
		(2 "B.Cu" signal "BOTTOM")
		(9 "F.Adhes" user "F.Adhesive")
		(11 "B.Adhes" user "B.Adhesive")
		(13 "F.Paste" user "Package Geometry/Pastemask Top")
		(15 "B.Paste" user "Package Geometry/Pastemask Bottom")
		(5 "F.SilkS" user "Ref Des/Silkscreen Top")
		(7 "B.SilkS" user "Ref Des/Silkscreen Bottom")
		(1 "F.Mask" user "Board Geometry/Soldermask Top")
		(3 "B.Mask" user "Board Geometry/Soldermask Bottom")
		(17 "Dwgs.User" user "User.Drawings")
		(19 "Cmts.User" user "User.Comments")
		(21 "Eco1.User" user "User.Eco1")
		(23 "Eco2.User" user "User.Eco2")
		(25 "Edge.Cuts" user "Board Geometry/Outline")
		(27 "Margin" user)
		(31 "F.CrtYd" user "Package Geometry/Place Bound Top")
		(29 "B.CrtYd" user "Package Geometry/Place Bound Bottom")
		(35 "F.Fab" user "Ref Des/Assembly Top")
		(33 "B.Fab" user "Ref Des/Assembly Bottom")
	)
	(footprint ""
		(layer "F.Cu")
		(at 38.227 -185.166 180)
		(property "Reference" "C188"
			(at 0 0 180)
			(layer "F.SilkS")
			(hide yes)
			(effects
				(font
					(size 1.27 1.27)
				)
			)
		)
		(property "Value" ""
			(at 0 0 180)
			(layer "F.Fab")
			(effects
				(font
					(size 1.27 1.27)
				)
			)
		)
		(duplicate_pad_numbers_are_jumpers no)
		(fp_line
			(start 0.7874 0.4064)
			(end -0.7874 0.4064)
			(stroke
				(width 0.1524)
				(type default)
			)
			(layer "F.SilkS")
		)
		(fp_line
			(start 0.7874 -0.4064)
			(end 0.7874 0.4064)
			(stroke
				(width 0.1524)
				(type default)
			)
			(layer "F.SilkS")
		)
		(fp_line
			(start -0.7874 0.4064)
			(end -0.7874 -0.4064)
			(stroke
				(width 0.1524)
				(type default)
			)
			(layer "F.SilkS")
		)
		(fp_line
			(start -0.7874 -0.4064)
			(end 0.7874 -0.4064)
			(stroke
				(width 0.1524)
				(type default)
			)
			(layer "F.SilkS")
		)
		(fp_line
			(start 0.67945 0.3048)
			(end 0.120396 0.3048)
			(stroke
				(width 0.1)
				(type default)
			)
			(layer "F.Fab")
		)
		(fp_line
			(start 0.67945 -0.3048)
			(end 0.67945 0.3048)
			(stroke
				(width 0.1)
				(type default)
			)
			(layer "F.Fab")
		)
		(fp_line
			(start 0.12065 -0.2794)
			(end 0.12065 -0.3048)
			(stroke
				(width 0.1)
				(type default)
			)
			(layer "F.Fab")
		)
		(fp_line
			(start 0.12065 -0.3048)
			(end 0.67945 -0.3048)
			(stroke
				(width 0.1)
				(type default)
			)
			(layer "F.Fab")
		)
		(fp_line
			(start 0.120396 0.3048)
			(end 0.120396 0.2794)
			(stroke
				(width 0.1)
				(type default)
			)
			(layer "F.Fab")
		)
		(fp_line
			(start 0.120396 0.2794)
			(end -0.12065 0.2794)
			(stroke
				(width 0.1)
				(type default)
			)
			(layer "F.Fab")
		)
		(fp_line
			(start -0.12065 0.3048)
			(end -0.67945 0.3048)
			(stroke
				(width 0.1)
				(type default)
			)
			(layer "F.Fab")
		)
		(fp_line
			(start -0.12065 0.2794)
			(end -0.12065 0.3048)
			(stroke
				(width 0.1)
				(type default)
			)
			(layer "F.Fab")
		)
		(fp_line
			(start -0.12065 -0.2794)
			(end 0.12065 -0.2794)
			(stroke
				(width 0.1)
				(type default)
			)
			(layer "F.Fab")
		)
		(fp_line
			(start -0.12065 -0.305054)
			(end -0.12065 -0.2794)
			(stroke
				(width 0.1)
				(type default)
			)
			(layer "F.Fab")
		)
		(fp_line
			(start -0.67945 0.3048)
			(end -0.67945 -0.305054)
			(stroke
				(width 0.1)
				(type default)
			)
			(layer "F.Fab")
		)
		(fp_line
			(start -0.67945 -0.305054)
			(end -0.12065 -0.305054)
			(stroke
				(width 0.1)
				(type default)
			)
			(layer "F.Fab")
		)
		(pad "1" smd circle
			(at -0.40005 0 180)
			(size 0 0)
			(layers "F.Cu" "F.Mask" "F.Paste")
			(net "P3V3_AUX")
		)
		(pad "2" smd circle
			(at 0.40005 0 180)
			(size 0 0)
			(layers "F.Cu" "F.Mask" "F.Paste")
			(net "GND")
		)
	)
	(footprint ""
		(layer "F.Cu")
		(at 25.527 -135.001)
		(property "Reference" "R5682"
			(at 0 0 0)
			(layer "F.SilkS")
			(hide yes)
			(effects
				(font
					(size 1.27 1.27)
				)
			)
		)
		(property "Value" ""
			(at 0 0 0)
			(layer "F.Fab")
			(effects
				(font
					(size 1.27 1.27)
				)
			)
		)
		(duplicate_pad_numbers_are_jumpers no)
		(fp_line
			(start -0.7874 -0.4064)
			(end 0.7874 -0.4064)
			(stroke
				(width 0.1524)
				(type default)
			)
			(layer "F.SilkS")
		)
		(fp_line
			(start -0.7874 0.4064)
			(end -0.7874 -0.4064)
			(stroke
				(width 0.1524)
				(type default)
			)
			(layer "F.SilkS")
		)
		(fp_line
			(start 0.7874 -0.4064)
			(end 0.7874 0.4064)
			(stroke
				(width 0.1524)
				(type default)
			)
			(layer "F.SilkS")
		)
		(fp_line
			(start 0.7874 0.4064)
			(end -0.7874 0.4064)
			(stroke
				(width 0.1524)
				(type default)
			)
			(layer "F.SilkS")
		)
		(fp_line
			(start -0.67945 -0.305054)
			(end -0.12065 -0.305054)
			(stroke
				(width 0.1)
				(type default)
			)
			(layer "F.Fab")
		)
		(fp_line
			(start -0.67945 0.3048)
			(end -0.67945 -0.305054)
			(stroke
				(width 0.1)
				(type default)
			)
			(layer "F.Fab")
		)
		(fp_line
			(start -0.12065 -0.305054)
			(end -0.12065 -0.2794)
			(stroke
				(width 0.1)
				(type default)
			)
			(layer "F.Fab")
		)
		(fp_line
			(start -0.12065 -0.2794)
			(end 0.12065 -0.2794)
			(stroke
				(width 0.1)
				(type default)
			)
			(layer "F.Fab")
		)
		(fp_line
			(start -0.12065 0.2794)
			(end -0.12065 0.3048)
			(stroke
				(width 0.1)
				(type default)
			)
			(layer "F.Fab")
		)
		(fp_line
			(start -0.12065 0.3048)
			(end -0.67945 0.3048)
			(stroke
				(width 0.1)
				(type default)
			)
			(layer "F.Fab")
		)
		(fp_line
			(start 0.120396 0.2794)
			(end -0.12065 0.2794)
			(stroke
				(width 0.1)
				(type default)
			)
			(layer "F.Fab")
		)
		(fp_line
			(start 0.120396 0.3048)
			(end 0.120396 0.2794)
			(stroke
				(width 0.1)
				(type default)
			)
			(layer "F.Fab")
		)
		(fp_line
			(start 0.12065 -0.3048)
			(end 0.67945 -0.3048)
			(stroke
				(width 0.1)
				(type default)
			)
			(layer "F.Fab")
		)
		(fp_line
			(start 0.12065 -0.2794)
			(end 0.12065 -0.3048)
			(stroke
				(width 0.1)
				(type default)
			)
			(layer "F.Fab")
		)
		(fp_line
			(start 0.67945 -0.3048)
			(end 0.67945 0.3048)
			(stroke
				(width 0.1)
				(type default)
			)
			(layer "F.Fab")
		)
		(fp_line
			(start 0.67945 0.3048)
			(end 0.120396 0.3048)
			(stroke
				(width 0.1)
				(type default)
			)
			(layer "F.Fab")
		)
		(pad "1" smd circle
			(at -0.40005 0)
			(size 0 0)
			(layers "F.Cu" "F.Mask" "F.Paste")
			(net "P3V3_AUX")
		)
		(pad "2" smd circle
			(at 0.40005 0)
			(size 0 0)
			(layers "F.Cu" "F.Mask" "F.Paste")
			(net "U330_FAN FAIL_N")
		)
	)
	(footprint ""
		(layer "F.Cu")
		(at 22.225 -123.317 90)
		(property "Reference" "C1938"
			(at 0 0 90)
			(layer "F.SilkS")
			(hide yes)
			(effects
				(font
					(size 1.27 1.27)
				)
			)
		)
		(property "Value" ""
			(at 0 0 90)
			(layer "F.Fab")
			(effects
				(font
					(size 1.27 1.27)
				)
			)
		)
		(duplicate_pad_numbers_are_jumpers no)
		(fp_line
			(start 0.7874 -0.4064)
			(end 0.7874 0.4064)
			(stroke
				(width 0.1524)
				(type default)
			)
			(layer "F.SilkS")
		)
		(fp_line
			(start -0.7874 -0.4064)
			(end 0.7874 -0.4064)
			(stroke
				(width 0.1524)
				(type default)
			)
			(layer "F.SilkS")
		)
		(fp_line
			(start 0.7874 0.4064)
			(end -0.7874 0.4064)
			(stroke
				(width 0.1524)
				(type default)
			)
			(layer "F.SilkS")
		)
		(fp_line
			(start -0.7874 0.4064)
			(end -0.7874 -0.4064)
			(stroke
				(width 0.1524)
				(type default)
			)
			(layer "F.SilkS")
		)
		(fp_line
			(start -0.12065 -0.305054)
			(end -0.12065 -0.2794)
			(stroke
				(width 0.1)
				(type default)
			)
			(layer "F.Fab")
		)
		(fp_line
			(start -0.67945 -0.305054)
			(end -0.12065 -0.305054)
			(stroke
				(width 0.1)
				(type default)
			)
			(layer "F.Fab")
		)
		(fp_line
			(start 0.67945 -0.3048)
			(end 0.67945 0.3048)
			(stroke
				(width 0.1)
				(type default)
			)
			(layer "F.Fab")
		)
		(fp_line
			(start 0.12065 -0.3048)
			(end 0.67945 -0.3048)
			(stroke
				(width 0.1)
				(type default)
			)
			(layer "F.Fab")
		)
		(fp_line
			(start 0.12065 -0.2794)
			(end 0.12065 -0.3048)
			(stroke
				(width 0.1)
				(type default)
			)
			(layer "F.Fab")
		)
		(fp_line
			(start -0.12065 -0.2794)
			(end 0.12065 -0.2794)
			(stroke
				(width 0.1)
				(type default)
			)
			(layer "F.Fab")
		)
		(fp_line
			(start 0.120396 0.2794)
			(end -0.12065 0.2794)
			(stroke
				(width 0.1)
				(type default)
			)
			(layer "F.Fab")
		)
		(fp_line
			(start -0.12065 0.2794)
			(end -0.12065 0.3048)
			(stroke
				(width 0.1)
				(type default)
			)
			(layer "F.Fab")
		)
		(fp_line
			(start 0.67945 0.3048)
			(end 0.120396 0.3048)
			(stroke
				(width 0.1)
				(type default)
			)
			(layer "F.Fab")
		)
		(fp_line
			(start 0.120396 0.3048)
			(end 0.120396 0.2794)
			(stroke
				(width 0.1)
				(type default)
			)
			(layer "F.Fab")
		)
		(fp_line
			(start -0.12065 0.3048)
			(end -0.67945 0.3048)
			(stroke
				(width 0.1)
				(type default)
			)
			(layer "F.Fab")
		)
		(fp_line
			(start -0.67945 0.3048)
			(end -0.67945 -0.305054)
			(stroke
				(width 0.1)
				(type default)
			)
			(layer "F.Fab")
		)
		(pad "1" smd circle
			(at -0.40005 0 90)
			(size 0 0)
			(layers "F.Cu" "F.Mask" "F.Paste")
			(net "GND")
		)
		(pad "2" smd circle
			(at 0.40005 0 90)
			(size 0 0)
			(layers "F.Cu" "F.Mask" "F.Paste")
			(net "P3V3_AUX")
		)
	)
	(footprint ""
		(layer "F.Cu")
		(at 32.004 -108.966)
		(property "Reference" "R5530"
			(at 0 0 0)
			(layer "F.SilkS")
			(hide yes)
			(effects
				(font
					(size 1.27 1.27)
				)
			)
		)
		(property "Value" ""
			(at 0 0 0)
			(layer "F.Fab")
			(effects
				(font
					(size 1.27 1.27)
				)
			)
		)
		(duplicate_pad_numbers_are_jumpers no)
		(fp_line
			(start -0.7874 -0.4064)
			(end 0.7874 -0.4064)
			(stroke
				(width 0.1524)
				(type default)
			)
			(layer "F.SilkS")
		)
		(fp_line
			(start -0.7874 0.4064)
			(end -0.7874 -0.4064)
			(stroke
				(width 0.1524)
				(type default)
			)
			(layer "F.SilkS")
		)
		(fp_line
			(start 0.7874 -0.4064)
			(end 0.7874 0.4064)
			(stroke
				(width 0.1524)
				(type default)
			)
			(layer "F.SilkS")
		)
		(fp_line
			(start 0.7874 0.4064)
			(end -0.7874 0.4064)
			(stroke
				(width 0.1524)
				(type default)
			)
			(layer "F.SilkS")
		)
		(fp_line
			(start -0.67945 -0.305054)
			(end -0.12065 -0.305054)
			(stroke
				(width 0.1)
				(type default)
			)
			(layer "F.Fab")
		)
		(fp_line
			(start -0.67945 0.3048)
			(end -0.67945 -0.305054)
			(stroke
				(width 0.1)
				(type default)
			)
			(layer "F.Fab")
		)
		(fp_line
			(start -0.12065 -0.305054)
			(end -0.12065 -0.2794)
			(stroke
				(width 0.1)
				(type default)
			)
			(layer "F.Fab")
		)
		(fp_line
			(start -0.12065 -0.2794)
			(end 0.12065 -0.2794)
			(stroke
				(width 0.1)
				(type default)
			)
			(layer "F.Fab")
		)
		(fp_line
			(start -0.12065 0.2794)
			(end -0.12065 0.3048)
			(stroke
				(width 0.1)
				(type default)
			)
			(layer "F.Fab")
		)
		(fp_line
			(start -0.12065 0.3048)
			(end -0.67945 0.3048)
			(stroke
				(width 0.1)
				(type default)
			)
			(layer "F.Fab")
		)
		(fp_line
			(start 0.120396 0.2794)
			(end -0.12065 0.2794)
			(stroke
				(width 0.1)
				(type default)
			)
			(layer "F.Fab")
		)
		(fp_line
			(start 0.120396 0.3048)
			(end 0.120396 0.2794)
			(stroke
				(width 0.1)
				(type default)
			)
			(layer "F.Fab")
		)
		(fp_line
			(start 0.12065 -0.3048)
			(end 0.67945 -0.3048)
			(stroke
				(width 0.1)
				(type default)
			)
			(layer "F.Fab")
		)
		(fp_line
			(start 0.12065 -0.2794)
			(end 0.12065 -0.3048)
			(stroke
				(width 0.1)
				(type default)
			)
			(layer "F.Fab")
		)
		(fp_line
			(start 0.67945 -0.3048)
			(end 0.67945 0.3048)
			(stroke
				(width 0.1)
				(type default)
			)
			(layer "F.Fab")
		)
		(fp_line
			(start 0.67945 0.3048)
			(end 0.120396 0.3048)
			(stroke
				(width 0.1)
				(type default)
			)
			(layer "F.Fab")
		)
		(pad "1" smd rect
			(at -0.40005 0 180)
			(size 0.4572 0.508)
			(layers "F.Cu" "F.Mask" "F.Paste")
			(net "P12V_LED_FAN2")
		)
		(pad "2" smd rect
			(at 0.40005 0 180)
			(size 0.4572 0.508)
			(layers "F.Cu" "F.Mask" "F.Paste")
			(net "FAN_2_FAIL_LED_R_N")
		)
	)
	(footprint ""
		(layer "F.Cu")
		(at 15.377922 -117.825012 180)
		(property "Reference" "D136"
			(at 5.471922 2.036318 0)
			(unlocked yes)
			(layer "F.SilkS")
			(effects
				(font
					(size 0.7874 0.5842)
					(thickness 0.1524)
				)
				(justify left)
			)
		)
		(property "Value" ""
			(at 0 0 180)
			(layer "F.Fab")
			(effects
				(font
					(size 1.27 1.27)
				)
			)
		)
		(duplicate_pad_numbers_are_jumpers no)
		(fp_line
			(start 2.032 0.7112)
			(end -1.651 0.7112)
			(stroke
				(width 0.1524)
				(type default)
			)
			(layer "F.SilkS")
		)
		(fp_line
			(start 2.032 -0.7112)
			(end 2.032 0.7112)
			(stroke
				(width 0.1524)
				(type default)
			)
			(layer "F.SilkS")
		)
		(fp_line
			(start 1.905 -0.6858)
			(end 1.905 0.6858)
			(stroke
				(width 0.1524)
				(type default)
			)
			(layer "F.SilkS")
		)
		(fp_line
			(start 1.778 0.6858)
			(end 1.778 -0.6858)
			(stroke
				(width 0.1524)
				(type default)
			)
			(layer "F.SilkS")
		)
		(fp_line
			(start 1.651 -0.6858)
			(end 1.651 0.6858)
			(stroke
				(width 0.1524)
				(type default)
			)
			(layer "F.SilkS")
		)
		(fp_line
			(start 0.299974 -0.500126)
			(end 0.299974 0.500126)
			(stroke
				(width 0.1524)
				(type default)
			)
			(layer "F.SilkS")
		)
		(fp_line
			(start 0.199898 0)
			(end -0.299974 -0.500126)
			(stroke
				(width 0.1524)
				(type default)
			)
			(layer "F.SilkS")
		)
		(fp_line
			(start -0.299974 0.500126)
			(end 0.199898 0)
			(stroke
				(width 0.1524)
				(type default)
			)
			(layer "F.SilkS")
		)
		(fp_line
			(start -0.299974 -0.500126)
			(end -0.299974 0.500126)
			(stroke
				(width 0.1524)
				(type default)
			)
			(layer "F.SilkS")
		)
		(fp_line
			(start -1.651 0.7112)
			(end -1.651 -0.7112)
			(stroke
				(width 0.1524)
				(type default)
			)
			(layer "F.SilkS")
		)
		(fp_line
			(start -1.651 -0.7112)
			(end 2.032 -0.7112)
			(stroke
				(width 0.1524)
				(type default)
			)
			(layer "F.SilkS")
		)
		(fp_line
			(start 1.35001 0.175006)
			(end 0.899922 0.175006)
			(stroke
				(width 0.1)
				(type default)
			)
			(layer "F.Fab")
		)
		(fp_line
			(start 1.35001 -0.225044)
			(end 1.35001 0.175006)
			(stroke
				(width 0.1)
				(type default)
			)
			(layer "F.Fab")
		)
		(fp_line
			(start 0.899922 0.700024)
			(end -0.899922 0.700024)
			(stroke
				(width 0.1)
				(type default)
			)
			(layer "F.Fab")
		)
		(fp_line
			(start 0.899922 0.175006)
			(end 0.899922 0.700024)
			(stroke
				(width 0.1)
				(type default)
			)
			(layer "F.Fab")
		)
		(fp_line
			(start 0.899922 -0.225044)
			(end 1.35001 -0.225044)
			(stroke
				(width 0.1)
				(type default)
			)
			(layer "F.Fab")
		)
		(fp_line
			(start 0.899922 -0.700024)
			(end 0.899922 -0.225044)
			(stroke
				(width 0.1)
				(type default)
			)
			(layer "F.Fab")
		)
		(fp_line
			(start 0.299974 -0.500126)
			(end 0.299974 0.500126)
			(stroke
				(width 0.1)
				(type default)
			)
			(layer "F.Fab")
		)
		(fp_line
			(start 0.199898 0)
			(end -0.299974 -0.500126)
			(stroke
				(width 0.1)
				(type default)
			)
			(layer "F.Fab")
		)
		(fp_line
			(start -0.299974 0.500126)
			(end 0.199898 0)
			(stroke
				(width 0.1)
				(type default)
			)
			(layer "F.Fab")
		)
		(fp_line
			(start -0.299974 -0.500126)
			(end -0.299974 0.500126)
			(stroke
				(width 0.1)
				(type default)
			)
			(layer "F.Fab")
		)
		(fp_line
			(start -0.899922 0.700024)
			(end -0.899922 0.175006)
			(stroke
				(width 0.1)
				(type default)
			)
			(layer "F.Fab")
		)
		(fp_line
			(start -0.899922 0.175006)
			(end -1.35001 0.175006)
			(stroke
				(width 0.1)
				(type default)
			)
			(layer "F.Fab")
		)
		(fp_line
			(start -0.899922 -0.225044)
			(end -0.899922 -0.700024)
			(stroke
				(width 0.1)
				(type default)
			)
			(layer "F.Fab")
		)
		(fp_line
			(start -0.899922 -0.700024)
			(end 0.899922 -0.700024)
			(stroke
				(width 0.1)
				(type default)
			)
			(layer "F.Fab")
		)
		(fp_line
			(start -1.35001 0.175006)
			(end -1.35001 -0.225044)
			(stroke
				(width 0.1)
				(type default)
			)
			(layer "F.Fab")
		)
		(fp_line
			(start -1.35001 -0.225044)
			(end -0.899922 -0.225044)
			(stroke
				(width 0.1)
				(type default)
			)
			(layer "F.Fab")
		)
		(fp_text user "-"
			(at 1.026922 0.824738 180)
			(unlocked yes)
			(layer "F.SilkS")
			(effects
				(font
					(size 1.905 1.4224)
					(thickness 0.1524)
				)
				(justify left)
			)
		)
		(fp_text user "+"
			(at -2.148078 1.205738 180)
			(unlocked yes)
			(layer "F.SilkS")
			(effects
				(font
					(size 1.905 1.4224)
					(thickness 0.1524)
				)
				(justify left)
			)
		)
		(fp_text user "-"
			(at 1.8288 -0.24765 180)
			(unlocked yes)
			(layer "F.Fab")
			(effects
				(font
					(size 1.905 1.4224)
					(thickness 0.1524)
				)
				(justify left)
			)
		)
		(fp_text user "+"
			(at -2.794 -0.19685 180)
			(unlocked yes)
			(layer "F.Fab")
			(effects
				(font
					(size 1.905 1.4224)
					(thickness 0.1524)
				)
				(justify left)
			)
		)
		(pad "1" smd rect
			(at -1.0922 0)
			(size 0.8128 0.8636)
			(layers "F.Cu" "F.Mask" "F.Paste")
			(net "FAN_5_TACH_OL_R")
		)
		(pad "2" smd rect
			(at 1.0922 0 180)
			(size 0.8128 0.8636)
			(layers "F.Cu" "F.Mask" "F.Paste")
			(net "FAN_5_TACH_OL_D")
		)
	)
)
